FILE_TYPE = MACRO_DRAWING;
SET COLOR_WIRE YELLOW;
SET COLOR_PROP ORANGE;
SET COLOR_DOT WHITE;
SET COLOR_ARC YELLOW;
SET COLOR_BODY GREEN;
SET COLOR_NOTE PURPLE;
SET PROP_DISPLAY VALUE;
SET PAGE_NUMBER P78;
FORCEADD QUANTA_TITLE_BLOCK_C..1
(0 0);
FORCEPROP 1 LAST CUSTOM_TXT_CDS <NAME_2>
J 0
(-3175 50);
FORCEPROP 1 LAST CUSTOM_TXT_CDS <NAME_1>
J 0
(-3175 175);
FORCEPROP 1 LAST CUSTOM_TXT_CDS <Q_NUMBER>
J 0
(-1403 103);
DISPLAY 1.212766 (-1403 103);
FORCEPROP 1 LAST CUSTOM_TXT_CDS <Q_PROJ>
J 0
(-2382 102);
DISPLAY 1.212766 (-2382 102);
FORCEPROP 1 LAST CUSTOM_TXT_CDS <Q_REV>
J 0
(-184 103);
DISPLAY 1.212766 (-184 103);
FORCEPROP 1 LAST CUSTOM_TXT_CDS <CON_LAST_MODIFIED>
J 0
(-1885 15);
DISPLAY 0.978723 (-1885 15);
FORCEPROP 1 LAST CUSTOM_TXT_CDS <CON_PAGE_NUM> OF <CON_TOTAL_PAGES>
J 0
(-446 18);
DISPLAY 0.978723 (-446 18);
FORCEPROP 1 LAST Q_TITLE Blank
J 0
(-9250 75);
DISPLAY 2.446809 (-9250 75);
PAINT GREEN (-9250 75);
FORCEPROP 2 LAST PAGE_BORDER TRUE
J 0
(-7890 5250);
DISPLAY 0.638298 (-7890 5250);
PAINT PINK (-7890 5250);
DISPLAY INVISIBLE (-7890 5250);
FORCEPROP 1 LAST CDS_LMAN_SYM_OUTLINE -9475,6775,100,-125
J 0
(0 0);
DISPLAY 0.468085 (0 0);
PAINT GREEN (0 0);
DISPLAY INVISIBLE (0 0);
FORCEPROP 2 LAST CDS_LIB pure_quanta
J 0
(0 0);
DISPLAY INVISIBLE (0 0);
FORCEPROP 2 LAST CDS_XR_PAGE_TITLE CR-79 : @T6G_MB_LIB.T6G(SCH_1):PAGE79
J 0
(-7890 5250);
DISPLAY 0.638298 (-7890 5250);
PAINT PINK (-7890 5250);
DISPLAY INVISIBLE (-7890 5250);
FORCEPROP 2 LAST CUSTOM_TXT_CDS <XR_PAGE_TITLE>
J 0
(-7890 5250);
DISPLAY 0.638298 (-7890 5250);
PAINT PINK (-7890 5250);
DISPLAY INVISIBLE (-7890 5250);
FORCEPROP 1 LAST COMMENT_BODY TRUE
J 0
(12 -13);
DISPLAY 0.978723 (12 -13);
PAINT GREEN (12 -13);
DISPLAY INVISIBLE (12 -13);
FORCEPROP 1 LAST Q_DEPT BU9
J 1
(-3763 49);
DISPLAY 1.957447 (-3763 49);
PAINT GREEN (-3763 49);
DISPLAY INVISIBLE (-3763 49);
FORCEPROP 0 LAST CDS_CON_LAST_MODIFIED Thu Aug 24 10:14:00 2023
J 0
(-1885 15);
DISPLAY INVISIBLE (-1885 15);
QUIT
